(kicad_pcb
	(version 20260206)
	(generator "pcbnew")
	(generator_version "10.0")
	(general
		(thickness 1.21888)
		(legacy_teardrops no)
	)
	(paper "A4")
	(title_block
		(title "timecard-v9 — TimeCard-DC-V9_EXP.PcbDoc")
		(comment 1 "Time Appliance Project (Time Card) / footprints 334-343 of 402")
	)
	(layers
		(0 "F.Cu" signal "TOP")
		(4 "In1.Cu" signal "SGND")
		(6 "In2.Cu" signal "IN1")
		(8 "In3.Cu" signal "IN2")
		(10 "In4.Cu" signal "SGND1")
		(2 "B.Cu" signal "BOTTOM")
		(9 "F.Adhes" user "F.Adhesive")
		(11 "B.Adhes" user "B.Adhesive")
		(13 "F.Paste" user "Top Paste")
		(15 "B.Paste" user "Bottom Paste")
		(5 "F.SilkS" user "Top Overlay")
		(7 "B.SilkS" user "Bottom Overlay")
		(1 "F.Mask" user "Top Solder")
		(3 "B.Mask" user "Bottom Solder")
		(17 "Dwgs.User" user "User.Drawings")
		(19 "Cmts.User" user "User.Comments")
		(21 "Eco1.User" user "User.Eco1")
		(23 "Eco2.User" user "User.Eco2")
		(25 "Edge.Cuts" user)
		(27 "Margin" user)
		(31 "F.CrtYd" user "Top Courtyard")
		(29 "B.CrtYd" user "Bottom Courtyard")
		(35 "F.Fab" user "Top Component Center")
		(33 "B.Fab" user "Bottom Component Center")
	)
	(footprint "Vault:FP-0402-L_1_0_1-W_0_5_0_1-IPC_C"
		(layer "B.Cu")
		(at 125.3216 54.4162 90)
		(property "Reference" "C74"
			(at 2.4968 0.026931 90)
			(unlocked yes)
			(layer "B.SilkS")
			(effects
				(font
					(size 0.762 0.762)
					(thickness 0.2032)
				)
				(justify mirror)
			)
		)
		(property "Value" "0.1uF_25V_0402"
			(at -2.465551 -9.813815 0)
			(unlocked yes)
			(layer "B.SilkS")
			(hide yes)
			(effects
				(font
					(size 0.762 0.762)
					(thickness 0.2032)
				)
				(justify mirror)
			)
		)
		(sheetname "10-M2_GPS")
		(sheetfile "10-M2_GPS.kicad_sch")
		(duplicate_pad_numbers_are_jumpers no)
		(fp_line
			(start -0.65607 -0.7)
			(end 0.65607 -0.7)
			(stroke
				(width 0.2)
				(type solid)
			)
			(layer "B.SilkS")
		)
		(fp_line
			(start -0.65607 0.7)
			(end 0.65607 0.7)
			(stroke
				(width 0.2)
				(type solid)
			)
			(layer "B.SilkS")
		)
		(fp_line
			(start 0.75607 -0.4)
			(end 0.75607 0.4)
			(stroke
				(width 0.2)
				(type solid)
			)
			(layer "B.CrtYd")
		)
		(fp_line
			(start -0.75606 -0.4)
			(end 0.75607 -0.4)
			(stroke
				(width 0.2)
				(type solid)
			)
			(layer "B.CrtYd")
		)
		(fp_line
			(start -0.75606 -0.4)
			(end -0.75606 0.4)
			(stroke
				(width 0.2)
				(type solid)
			)
			(layer "B.CrtYd")
		)
		(fp_line
			(start -0.75606 0.4)
			(end 0.75607 0.4)
			(stroke
				(width 0.2)
				(type solid)
			)
			(layer "B.CrtYd")
		)
		(fp_line
			(start 0 -0.5)
			(end 0 0.5)
			(stroke
				(width 0.1)
				(type solid)
			)
			(layer "B.Fab")
		)
		(fp_line
			(start 0.75607 -0.4)
			(end 0.75607 0.4)
			(stroke
				(width 0.2)
				(type solid)
			)
			(layer "B.Fab")
		)
		(fp_line
			(start -0.75606 -0.4)
			(end 0.75607 -0.4)
			(stroke
				(width 0.2)
				(type solid)
			)
			(layer "B.Fab")
		)
		(fp_line
			(start -0.75606 -0.4)
			(end -0.75606 0.4)
			(stroke
				(width 0.2)
				(type solid)
			)
			(layer "B.Fab")
		)
		(fp_line
			(start -0.5 0)
			(end 0.5 0)
			(stroke
				(width 0.1)
				(type solid)
			)
			(layer "B.Fab")
		)
		(fp_line
			(start -0.75606 0.4)
			(end 0.75607 0.4)
			(stroke
				(width 0.2)
				(type solid)
			)
			(layer "B.Fab")
		)
		(fp_text user "${REFERENCE}"
			(at -0.00001 -0.09602 270)
			(unlocked yes)
			(layer "B.Fab")
			(effects
				(font
					(face "Arial")
					(size 0.63 0.63)
					(thickness 0.1)
				)
				(justify left bottom mirror)
			)
		)
		(pad "1" smd rect
			(at -0.36553 0 90)
			(size 0.58106 0.51213)
			(layers "B.Cu" "B.Mask" "B.Paste")
			(net "+3.3V")
			(solder_mask_margin 0)
			(solder_paste_margin 0)
		)
		(pad "2" smd rect
			(at 0.36554 0 90)
			(size 0.58106 0.51213)
			(layers "B.Cu" "B.Mask" "B.Paste")
			(net "GND")
			(solder_mask_margin 0)
			(solder_paste_margin 0)
		)
	)
	(footprint "Vault:FP-0402-L_1_0_1-W_0_5_0_1-IPC_C"
		(layer "B.Cu")
		(at 210.41727 124.16632 90)
		(property "Reference" "C110"
			(at 1.99612 0.131251 90)
			(unlocked yes)
			(layer "B.SilkS")
			(effects
				(font
					(size 0.762 0.762)
					(thickness 0.254)
				)
				(justify mirror)
			)
		)
		(property "Value" "0.1uF_25V_0402"
			(at -2.465551 -9.864615 0)
			(unlocked yes)
			(layer "B.SilkS")
			(hide yes)
			(effects
				(font
					(size 0.762 0.762)
					(thickness 0.254)
				)
				(justify mirror)
			)
		)
		(sheetname "09-USBUart_PPSMUX_UARTMUX")
		(sheetfile "09-USBUart_PPSMUX_UARTMUX.kicad_sch")
		(duplicate_pad_numbers_are_jumpers no)
		(fp_line
			(start -0.65607 -0.7)
			(end 0.65607 -0.7)
			(stroke
				(width 0.2)
				(type solid)
			)
			(layer "B.SilkS")
		)
		(fp_line
			(start -0.65607 0.7)
			(end 0.65607 0.7)
			(stroke
				(width 0.2)
				(type solid)
			)
			(layer "B.SilkS")
		)
		(fp_line
			(start 0.75607 -0.4)
			(end 0.75607 0.4)
			(stroke
				(width 0.2)
				(type solid)
			)
			(layer "B.CrtYd")
		)
		(fp_line
			(start -0.75607 -0.4)
			(end 0.75607 -0.4)
			(stroke
				(width 0.2)
				(type solid)
			)
			(layer "B.CrtYd")
		)
		(fp_line
			(start -0.75607 -0.4)
			(end -0.75607 0.4)
			(stroke
				(width 0.2)
				(type solid)
			)
			(layer "B.CrtYd")
		)
		(fp_line
			(start -0.75607 0.4)
			(end 0.75607 0.4)
			(stroke
				(width 0.2)
				(type solid)
			)
			(layer "B.CrtYd")
		)
		(fp_line
			(start 0 -0.5)
			(end 0 0.5)
			(stroke
				(width 0.1)
				(type solid)
			)
			(layer "B.Fab")
		)
		(fp_line
			(start 0.75607 -0.4)
			(end 0.75607 0.4)
			(stroke
				(width 0.2)
				(type solid)
			)
			(layer "B.Fab")
		)
		(fp_line
			(start -0.75607 -0.4)
			(end 0.75607 -0.4)
			(stroke
				(width 0.2)
				(type solid)
			)
			(layer "B.Fab")
		)
		(fp_line
			(start -0.75607 -0.4)
			(end -0.75607 0.4)
			(stroke
				(width 0.2)
				(type solid)
			)
			(layer "B.Fab")
		)
		(fp_line
			(start -0.5 0)
			(end 0.5 0)
			(stroke
				(width 0.1)
				(type solid)
			)
			(layer "B.Fab")
		)
		(fp_line
			(start -0.75607 0.4)
			(end 0.75607 0.4)
			(stroke
				(width 0.2)
				(type solid)
			)
			(layer "B.Fab")
		)
		(fp_text user "${REFERENCE}"
			(at -0.00001 -0.09602 270)
			(unlocked yes)
			(layer "B.Fab")
			(effects
				(font
					(face "Arial")
					(size 0.63 0.63)
					(thickness 0.1)
				)
				(justify left bottom mirror)
			)
		)
		(pad "1" smd rect
			(at -0.36554 0 90)
			(size 0.58106 0.51213)
			(layers "B.Cu" "B.Mask" "B.Paste")
			(net "GNSS2_P3V3")
			(solder_mask_margin 0)
			(solder_paste_margin 0)
		)
		(pad "2" smd rect
			(at 0.36554 0 90)
			(size 0.58106 0.51213)
			(layers "B.Cu" "B.Mask" "B.Paste")
			(net "GND")
			(solder_mask_margin 0)
			(solder_paste_margin 0)
		)
	)
	(footprint "Vault:RESC1005X40X25NL10T10"
		(layer "B.Cu")
		(at 95.2756 59.4162)
		(property "Reference" "R5"
			(at -0.554 0.906655 180)
			(unlocked yes)
			(layer "B.SilkS")
			(effects
				(font
					(size 0.762 0.762)
					(thickness 0.2286)
				)
				(justify left bottom mirror)
			)
		)
		(property "Value" "4.7K_1%_0402"
			(at -0.6183 32.959045 0)
			(unlocked yes)
			(layer "B.SilkS")
			(hide yes)
			(effects
				(font
					(size 0.762 0.762)
					(thickness 0.2286)
				)
				(justify left bottom mirror)
			)
		)
		(sheetname "03-POWER")
		(sheetfile "03-POWER.kicad_sch")
		(duplicate_pad_numbers_are_jumpers no)
		(pad "1" smd rect
			(at -0.425 0 270)
			(size 0.6 0.65)
			(layers "B.Cu" "B.Mask" "B.Paste")
			(net "NetR5_1")
		)
		(pad "2" smd rect
			(at 0.425 0 270)
			(size 0.6 0.65)
			(layers "B.Cu" "B.Mask" "B.Paste")
			(net "+12V")
		)
	)
	(footprint "Vault:FP-0603-L_1_6_0_2-W_0_8_0-MFG"
		(layer "B.Cu")
		(at 170.15457 89.4162 180)
		(property "Reference" "C85"
			(at 0.36157 1.573069 0)
			(unlocked yes)
			(layer "B.SilkS")
			(effects
				(font
					(size 0.762 0.762)
					(thickness 0.2286)
				)
				(justify mirror)
			)
		)
		(property "Value" "10uF_16V_0603"
			(at -2.871951 -8.95046 90)
			(unlocked yes)
			(layer "B.SilkS")
			(hide yes)
			(effects
				(font
					(size 0.762 0.762)
					(thickness 0.2286)
				)
				(justify mirror)
			)
		)
		(sheetname "03-POWER")
		(sheetfile "03-POWER.kicad_sch")
		(duplicate_pad_numbers_are_jumpers no)
		(fp_line
			(start 0.9 0.825)
			(end -0.9 0.825)
			(stroke
				(width 0.2)
				(type solid)
			)
			(layer "B.SilkS")
		)
		(fp_line
			(start 0.9 -0.825)
			(end -0.9 -0.825)
			(stroke
				(width 0.2)
				(type solid)
			)
			(layer "B.SilkS")
		)
		(fp_line
			(start 1.15 0.6)
			(end -1.15 0.6)
			(stroke
				(width 0.2)
				(type solid)
			)
			(layer "B.CrtYd")
		)
		(fp_line
			(start 1.15 -0.6)
			(end 1.15 0.6)
			(stroke
				(width 0.2)
				(type solid)
			)
			(layer "B.CrtYd")
		)
		(fp_line
			(start 1.15 -0.6)
			(end -1.15 -0.6)
			(stroke
				(width 0.2)
				(type solid)
			)
			(layer "B.CrtYd")
		)
		(fp_line
			(start -1.15 -0.6)
			(end -1.15 0.6)
			(stroke
				(width 0.2)
				(type solid)
			)
			(layer "B.CrtYd")
		)
		(fp_line
			(start 1.15 0.6)
			(end -1.15 0.6)
			(stroke
				(width 0.2)
				(type solid)
			)
			(layer "B.Fab")
		)
		(fp_line
			(start 1.15 -0.6)
			(end 1.15 0.6)
			(stroke
				(width 0.2)
				(type solid)
			)
			(layer "B.Fab")
		)
		(fp_line
			(start 1.15 -0.6)
			(end -1.15 -0.6)
			(stroke
				(width 0.2)
				(type solid)
			)
			(layer "B.Fab")
		)
		(fp_line
			(start 0.5 0)
			(end -0.5 0)
			(stroke
				(width 0.1)
				(type solid)
			)
			(layer "B.Fab")
		)
		(fp_line
			(start 0 -0.5)
			(end 0 0.5)
			(stroke
				(width 0.1)
				(type solid)
			)
			(layer "B.Fab")
		)
		(fp_line
			(start -1.15 -0.6)
			(end -1.15 0.6)
			(stroke
				(width 0.2)
				(type solid)
			)
			(layer "B.Fab")
		)
		(fp_text user "${REFERENCE}"
			(at -0.00001 -0.09602 360)
			(unlocked yes)
			(layer "B.Fab")
			(effects
				(font
					(face "Arial")
					(size 0.63 0.63)
					(thickness 0.1)
				)
				(justify left bottom mirror)
			)
		)
		(pad "1" smd rect
			(at -0.7 0 180)
			(size 0.7 0.7)
			(layers "B.Cu" "B.Mask" "B.Paste")
			(net "+3.3V")
			(solder_mask_margin 0)
			(solder_paste_margin 0)
		)
		(pad "2" smd rect
			(at 0.7 0 180)
			(size 0.7 0.7)
			(layers "B.Cu" "B.Mask" "B.Paste")
			(net "GND")
			(solder_mask_margin 0)
			(solder_paste_margin 0)
		)
	)
	(footprint "Vault:RESC1005X40X25NL10T10"
		(layer "B.Cu")
		(at 207.14172 117.4412 180)
		(property "Reference" "R137"
			(at -2.77668 -0.201921 0)
			(unlocked yes)
			(layer "B.SilkS")
			(effects
				(font
					(size 0.762 0.762)
					(thickness 0.2032)
				)
				(justify mirror)
			)
		)
		(property "Value" "4.7K_1%_0402"
			(at -2.732271 -8.747465 90)
			(unlocked yes)
			(layer "B.SilkS")
			(hide yes)
			(effects
				(font
					(size 0.762 0.762)
					(thickness 0.2032)
				)
				(justify mirror)
			)
		)
		(sheetname "10-M2_GPS")
		(sheetfile "10-M2_GPS.kicad_sch")
		(duplicate_pad_numbers_are_jumpers no)
		(pad "1" smd rect
			(at -0.425 0 90)
			(size 0.6 0.65)
			(layers "B.Cu" "B.Mask" "B.Paste")
			(net "GPS2_PIN15")
		)
		(pad "2" smd rect
			(at 0.425 0 90)
			(size 0.6 0.65)
			(layers "B.Cu" "B.Mask" "B.Paste")
			(net "GNSS2_P3V3")
		)
	)
	(footprint "Vault:RESC1005X40X25NL10T10"
		(layer "B.Cu")
		(at 207.65181 118.8412 180)
		(property "Reference" "R136"
			(at -2.96659 -0.001921 0)
			(unlocked yes)
			(layer "B.SilkS")
			(effects
				(font
					(size 0.762 0.762)
					(thickness 0.2032)
				)
				(justify mirror)
			)
		)
		(property "Value" "4.7K_1%_0402"
			(at -2.732271 -8.747465 90)
			(unlocked yes)
			(layer "B.SilkS")
			(hide yes)
			(effects
				(font
					(size 0.762 0.762)
					(thickness 0.2032)
				)
				(justify mirror)
			)
		)
		(sheetname "10-M2_GPS")
		(sheetfile "10-M2_GPS.kicad_sch")
		(duplicate_pad_numbers_are_jumpers no)
		(pad "1" smd rect
			(at -0.425 0 90)
			(size 0.6 0.65)
			(layers "B.Cu" "B.Mask" "B.Paste")
			(net "GPS2_PIN14")
		)
		(pad "2" smd rect
			(at 0.425 0 90)
			(size 0.6 0.65)
			(layers "B.Cu" "B.Mask" "B.Paste")
			(net "GNSS2_P3V3")
		)
	)
	(footprint "Vault:CAPC1005X56X25NL10T15"
		(layer "B.Cu")
		(at 227.3216 70.3162)
		(property "Reference" "C19"
			(at 1.046 -1.141655 0)
			(unlocked yes)
			(layer "B.SilkS")
			(effects
				(font
					(size 0.762 0.762)
					(thickness 0.2286)
				)
				(justify left bottom mirror)
			)
		)
		(property "Value" "0.1uF_25V_0402"
			(at -9.4735 -2.041355 0)
			(unlocked yes)
			(layer "B.SilkS")
			(hide yes)
			(effects
				(font
					(size 0.762 0.762)
					(thickness 0.2286)
				)
				(justify left bottom mirror)
			)
		)
		(sheetname "03-POWER")
		(sheetfile "03-POWER.kicad_sch")
		(duplicate_pad_numbers_are_jumpers no)
		(pad "1" smd rect
			(at -0.44 0 270)
			(size 0.64 0.68)
			(layers "B.Cu" "B.Mask" "B.Paste")
			(net "GND")
		)
		(pad "2" smd rect
			(at 0.44 0 270)
			(size 0.64 0.68)
			(layers "B.Cu" "B.Mask" "B.Paste")
			(net "+3.3V")
		)
	)
	(footprint "LotusSound:IC_TPS2116"
		(layer "B.Cu")
		(at 216.33831 126.11791)
		(property "Reference" "U34"
			(at -8.29034 6.754171 0)
			(unlocked yes)
			(layer "B.SilkS")
			(hide yes)
			(effects
				(font
					(size 0.762 0.762)
					(thickness 0.2032)
				)
				(justify mirror)
			)
		)
		(property "Value" "TPS2116DRLR"
			(at -14.143155 12.458271 0)
			(unlocked yes)
			(layer "B.SilkS")
			(hide yes)
			(effects
				(font
					(size 0.762 0.762)
					(thickness 0.2032)
				)
				(justify mirror)
			)
		)
		(sheetname "09-USBUart_PPSMUX_UARTMUX")
		(sheetfile "09-USBUart_PPSMUX_UARTMUX.kicad_sch")
		(duplicate_pad_numbers_are_jumpers no)
		(fp_line
			(start -0.6 -1.23)
			(end 0.6 -1.23)
			(stroke
				(width 0.127)
				(type solid)
			)
			(layer "B.SilkS")
		)
		(fp_line
			(start -0.6 1.23)
			(end 0.6 1.23)
			(stroke
				(width 0.127)
				(type solid)
			)
			(layer "B.SilkS")
		)
		(fp_circle
			(center -1.6 0.75001)
			(end -1.6 0.65001)
			(stroke
				(width 0.2)
				(type solid)
			)
			(fill no)
			(layer "B.SilkS")
		)
		(pad "1" smd roundrect
			(at -0.735 0.75001)
			(size 0.66 0.32)
			(layers "B.Cu" "B.Mask" "B.Paste")
			(roundrect_rratio 0.125)
			(net "GND")
		)
		(pad "2" smd roundrect
			(at -0.735 0.25)
			(size 0.66 0.32)
			(layers "B.Cu" "B.Mask" "B.Paste")
			(roundrect_rratio 0.125)
			(net "GNSS2_P5V0")
		)
		(pad "3" smd roundrect
			(at -0.735 -0.25)
			(size 0.66 0.32)
			(layers "B.Cu" "B.Mask" "B.Paste")
			(roundrect_rratio 0.125)
			(net "+5.0V")
		)
		(pad "4" smd roundrect
			(at -0.735 -0.75)
			(size 0.66 0.32)
			(layers "B.Cu" "B.Mask" "B.Paste")
			(roundrect_rratio 0.125)
			(net "NetR180_1")
		)
		(pad "5" smd roundrect
			(at 0.735 -0.75)
			(size 0.66 0.32)
			(layers "B.Cu" "B.Mask" "B.Paste")
			(roundrect_rratio 0.125)
			(net "+5.0V")
		)
		(pad "6" smd roundrect
			(at 0.735 -0.25)
			(size 0.66 0.32)
			(layers "B.Cu" "B.Mask" "B.Paste")
			(roundrect_rratio 0.125)
			(net "FTDI_VBUS")
		)
		(pad "7" smd roundrect
			(at 0.735 0.25)
			(size 0.66 0.32)
			(layers "B.Cu" "B.Mask" "B.Paste")
			(roundrect_rratio 0.125)
			(net "GNSS2_P5V0")
		)
		(pad "8" smd roundrect
			(at 0.735 0.75001)
			(size 0.66 0.32)
			(layers "B.Cu" "B.Mask" "B.Paste")
			(roundrect_rratio 0.125)
		)
	)
	(footprint "Vault:FP-0402-L_1_0_1-W_0_5_0_1-IPC_C"
		(layer "B.Cu")
		(at 143.7216 104.7162 -90)
		(property "Reference" "C96"
			(at 0.2286 1.595239 90)
			(unlocked yes)
			(layer "B.SilkS")
			(effects
				(font
					(size 0.762 0.762)
					(thickness 0.2286)
				)
				(justify mirror)
			)
		)
		(property "Value" "0.1uF_25V_0402"
			(at -2.465551 -9.839205 180)
			(unlocked yes)
			(layer "B.SilkS")
			(hide yes)
			(effects
				(font
					(size 0.762 0.762)
					(thickness 0.2286)
				)
				(justify mirror)
			)
		)
		(sheetname "09-USBUart_PPSMUX_UARTMUX")
		(sheetfile "09-USBUart_PPSMUX_UARTMUX.kicad_sch")
		(duplicate_pad_numbers_are_jumpers no)
		(fp_line
			(start 0.65607 0.7)
			(end -0.65607 0.7)
			(stroke
				(width 0.2)
				(type solid)
			)
			(layer "B.SilkS")
		)
		(fp_line
			(start 0.65607 -0.7)
			(end -0.65607 -0.7)
			(stroke
				(width 0.2)
				(type solid)
			)
			(layer "B.SilkS")
		)
		(fp_line
			(start -0.75607 0.4)
			(end -0.75607 -0.4)
			(stroke
				(width 0.2)
				(type solid)
			)
			(layer "B.CrtYd")
		)
		(fp_line
			(start 0.75607 0.4)
			(end -0.75607 0.4)
			(stroke
				(width 0.2)
				(type solid)
			)
			(layer "B.CrtYd")
		)
		(fp_line
			(start 0.75607 0.4)
			(end 0.75607 -0.4)
			(stroke
				(width 0.2)
				(type solid)
			)
			(layer "B.CrtYd")
		)
		(fp_line
			(start 0.75607 -0.4)
			(end -0.75607 -0.4)
			(stroke
				(width 0.2)
				(type solid)
			)
			(layer "B.CrtYd")
		)
		(fp_line
			(start 0 0.5)
			(end 0 -0.5)
			(stroke
				(width 0.1)
				(type solid)
			)
			(layer "B.Fab")
		)
		(fp_line
			(start -0.75607 0.4)
			(end -0.75607 -0.4)
			(stroke
				(width 0.2)
				(type solid)
			)
			(layer "B.Fab")
		)
		(fp_line
			(start 0.75607 0.4)
			(end -0.75607 0.4)
			(stroke
				(width 0.2)
				(type solid)
			)
			(layer "B.Fab")
		)
		(fp_line
			(start 0.75607 0.4)
			(end 0.75607 -0.4)
			(stroke
				(width 0.2)
				(type solid)
			)
			(layer "B.Fab")
		)
		(fp_line
			(start 0.5 0)
			(end -0.5 0)
			(stroke
				(width 0.1)
				(type solid)
			)
			(layer "B.Fab")
		)
		(fp_line
			(start 0.75607 -0.4)
			(end -0.75607 -0.4)
			(stroke
				(width 0.2)
				(type solid)
			)
			(layer "B.Fab")
		)
		(fp_text user "${REFERENCE}"
			(at -0.00001 -0.09602 90)
			(unlocked yes)
			(layer "B.Fab")
			(effects
				(font
					(face "Arial")
					(size 0.63 0.63)
					(thickness 0.1)
				)
				(justify left bottom mirror)
			)
		)
		(pad "1" smd rect
			(at -0.36554 0 270)
			(size 0.58106 0.51213)
			(layers "B.Cu" "B.Mask" "B.Paste")
			(net "+3.3V")
			(solder_mask_margin 0)
			(solder_paste_margin 0)
		)
		(pad "2" smd rect
			(at 0.36554 0 270)
			(size 0.58106 0.51213)
			(layers "B.Cu" "B.Mask" "B.Paste")
			(net "GND")
			(solder_mask_margin 0)
			(solder_paste_margin 0)
		)
	)
	(footprint "Vault:CAPC1608X87X45ML20T05"
		(layer "B.Cu")
		(at 103.9741 71.7286 180)
		(property "Reference" "C61"
			(at -1.39159 1.120785 0)
			(unlocked yes)
			(layer "B.SilkS")
			(effects
				(font
					(size 0.762 0.762)
					(thickness 0.2286)
				)
				(justify left bottom mirror)
			)
		)
		(property "Value" "0.1uF"
			(at -0.2921 -3.382645 0)
			(unlocked yes)
			(layer "B.SilkS")
			(hide yes)
			(effects
				(font
					(size 0.762 0.762)
					(thickness 0.2286)
				)
				(justify left bottom mirror)
			)
		)
		(sheetname "05-GPS_IMU_SENSORS")
		(sheetfile "05-GPS_IMU_SENSORS.kicad_sch")
		(duplicate_pad_numbers_are_jumpers no)
		(pad "1" smd rect
			(at -0.7 0 90)
			(size 1.1 1.05)
			(layers "B.Cu" "B.Mask" "B.Paste")
			(net "GND")
		)
		(pad "2" smd rect
			(at 0.7 0 90)
			(size 1.1 1.05)
			(layers "B.Cu" "B.Mask" "B.Paste")
			(net "+5.0V")
		)
	)
)
